(kicad_pcb
	(version 20260206)
	(generator "pcbnew")
	(generator_version "10.0")
	(general
		(thickness 1.6)
		(legacy_teardrops no)
	)
	(paper "A4")
	(title_block
		(title "peb — Lightning_PEB_BRD.brd")
		(comment 1 "Lightning (Wiwynn / Facebook NVMe JBOF) / footprints 247-253 of 2563")
	)
	(layers
		(0 "F.Cu" signal "TOP")
		(4 "In1.Cu" signal "L2GND")
		(6 "In2.Cu" signal "L3")
		(8 "In3.Cu" signal "L4VCC")
		(10 "In4.Cu" signal "L5VCC")
		(12 "In5.Cu" signal "L6")
		(14 "In6.Cu" signal "L7GND")
		(2 "B.Cu" signal "BOTTOM")
		(9 "F.Adhes" user "F.Adhesive")
		(11 "B.Adhes" user "B.Adhesive")
		(13 "F.Paste" user "Package Geometry/Pastemask Top")
		(15 "B.Paste" user "Package Geometry/Pastemask Bottom")
		(5 "F.SilkS" user "Ref Des/Silkscreen Top")
		(7 "B.SilkS" user "Ref Des/Silkscreen Bottom")
		(1 "F.Mask" user "Board Geometry/Soldermask Top")
		(3 "B.Mask" user "Board Geometry/Soldermask Bottom")
		(17 "Dwgs.User" user "User.Drawings")
		(19 "Cmts.User" user "User.Comments")
		(21 "Eco1.User" user "User.Eco1")
		(23 "Eco2.User" user "User.Eco2")
		(25 "Edge.Cuts" user "Board Geometry/Outline")
		(27 "Margin" user)
		(31 "F.CrtYd" user "Package Geometry/Place Bound Top")
		(29 "B.CrtYd" user "Package Geometry/Place Bound Bottom")
		(35 "F.Fab" user "Ref Des/Assembly Top")
		(33 "B.Fab" user "Ref Des/Assembly Bottom")
	)
	(footprint ""
		(layer "F.Cu")
		(at 129.388362 -39.469568 180)
		(property "Reference" "Q27"
			(at 0 0 180)
			(layer "F.SilkS")
			(hide yes)
			(effects
				(font
					(size 1.27 1.27)
				)
			)
		)
		(property "Value" "2N7002K-1-GP"
			(at 0.127 -8.9662 180)
			(unlocked yes)
			(layer "F.Fab")
			(hide yes)
			(effects
				(font
					(size 1.016 1.016)
					(thickness 0.1524)
				)
			)
		)
		(property "Device Type" "SOT23DGS2D4H44"
			(at 0.127 -10.4902 180)
			(unlocked yes)
			(layer "F.Fab")
			(hide yes)
			(effects
				(font
					(size 1.016 1.016)
					(thickness 0.1524)
				)
			)
		)
		(duplicate_pad_numbers_are_jumpers no)
		(fp_line
			(start 1.651 1.778)
			(end 1.651 -1.778)
			(stroke
				(width 0.1524)
				(type default)
			)
			(layer "F.SilkS")
		)
		(fp_line
			(start 1.651 -1.778)
			(end -1.651 -1.778)
			(stroke
				(width 0.1524)
				(type default)
			)
			(layer "F.SilkS")
		)
		(fp_line
			(start -1.651 1.778)
			(end 1.651 1.778)
			(stroke
				(width 0.1524)
				(type default)
			)
			(layer "F.SilkS")
		)
		(fp_line
			(start -1.651 -1.778)
			(end -1.651 1.778)
			(stroke
				(width 0.1524)
				(type default)
			)
			(layer "F.SilkS")
		)
		(fp_poly
			(pts
				(xy -1.778 1.8796) (xy -1.778 -1.8796) (xy 1.778 -1.8796) (xy 1.778 1.8796)
			)
			(stroke
				(width 0)
				(type default)
			)
			(fill no)
			(layer "F.CrtYd")
		)
		(fp_poly
			(pts
				(xy -1.778 1.8796) (xy -1.778 -1.8796) (xy 1.778 -1.8796) (xy 1.778 1.8796)
			)
			(stroke
				(width 0)
				(type default)
			)
			(fill no)
			(layer "F.Fab")
		)
		(pad "D" smd custom
			(at 0 -0.9525 180)
			(size 0.1905 0.1905)
			(layers "F.Cu" "F.Mask" "F.Paste")
			(net "LED_Q_4")
			(options
				(clearance outline)
				(anchor circle)
			)
			(primitives
				(gr_poly
					(pts
						(arc
							(start -0.1778 0.5715)
							(mid -0.321484 0.511984)
							(end -0.381 0.3683)
						)
						(arc
							(start -0.381 -0.3683)
							(mid -0.321484 -0.511984)
							(end -0.1778 -0.5715)
						)
						(arc
							(start 0.1778 -0.5715)
							(mid 0.321484 -0.511984)
							(end 0.381 -0.3683)
						)
						(arc
							(start 0.381 0.3683)
							(mid 0.321484 0.511984)
							(end 0.1778 0.5715)
						)
					)
					(width 0)
					(fill yes)
				)
			)
		)
		(pad "G" smd custom
			(at -0.98425 0.9525 180)
			(size 0.1905 0.1905)
			(layers "F.Cu" "F.Mask" "F.Paste")
			(net "UPLINK4_R")
			(options
				(clearance outline)
				(anchor circle)
			)
			(primitives
				(gr_poly
					(pts
						(arc
							(start -0.1778 0.5715)
							(mid -0.321484 0.511984)
							(end -0.381 0.3683)
						)
						(arc
							(start -0.381 -0.3683)
							(mid -0.321484 -0.511984)
							(end -0.1778 -0.5715)
						)
						(arc
							(start 0.1778 -0.5715)
							(mid 0.321484 -0.511984)
							(end 0.381 -0.3683)
						)
						(arc
							(start 0.381 0.3683)
							(mid 0.321484 0.511984)
							(end 0.1778 0.5715)
						)
					)
					(width 0)
					(fill yes)
				)
			)
		)
		(pad "S" smd custom
			(at 0.98425 0.9525 180)
			(size 0.1905 0.1905)
			(layers "F.Cu" "F.Mask" "F.Paste")
			(net "GND")
			(options
				(clearance outline)
				(anchor circle)
			)
			(primitives
				(gr_poly
					(pts
						(arc
							(start -0.1778 0.5715)
							(mid -0.321484 0.511984)
							(end -0.381 0.3683)
						)
						(arc
							(start -0.381 -0.3683)
							(mid -0.321484 -0.511984)
							(end -0.1778 -0.5715)
						)
						(arc
							(start 0.1778 -0.5715)
							(mid 0.321484 -0.511984)
							(end 0.381 -0.3683)
						)
						(arc
							(start 0.381 0.3683)
							(mid 0.321484 0.511984)
							(end 0.1778 0.5715)
						)
					)
					(width 0)
					(fill yes)
				)
			)
		)
	)
	(footprint ""
		(layer "F.Cu")
		(at 128.8542 -45.8978 180)
		(property "Reference" "R762"
			(at 0 0 180)
			(layer "F.SilkS")
			(hide yes)
			(effects
				(font
					(size 1.27 1.27)
				)
			)
		)
		(property "Value" "0R2J-2-GP"
			(at 0.064008 -3.993896 180)
			(unlocked yes)
			(layer "F.Fab")
			(hide yes)
			(effects
				(font
					(size 1.016 1.016)
					(thickness 0.1524)
				)
			)
		)
		(property "Device Type" "R402H16"
			(at 0.064008 -5.517896 180)
			(unlocked yes)
			(layer "F.Fab")
			(hide yes)
			(effects
				(font
					(size 1.016 1.016)
					(thickness 0.1524)
				)
			)
		)
		(duplicate_pad_numbers_are_jumpers no)
		(fp_line
			(start 0.508 -0.9398)
			(end -0.508 -0.9398)
			(stroke
				(width 0.1524)
				(type default)
			)
			(layer "F.SilkS")
		)
		(fp_line
			(start -0.508 -0.9398)
			(end -0.508 0.9398)
			(stroke
				(width 0.1524)
				(type default)
			)
			(layer "F.SilkS")
		)
		(fp_rect
			(start -0.508 0.9398)
			(end 0.508 -0.9398)
			(stroke
				(width 0)
				(type default)
			)
			(fill no)
			(layer "F.CrtYd")
		)
		(fp_rect
			(start -0.508 0.9398)
			(end 0.508 -0.9398)
			(stroke
				(width 0)
				(type default)
			)
			(fill no)
			(layer "F.Fab")
		)
		(pad "1" smd custom
			(at 0 -0.4445 180)
			(size 0.1397 0.1397)
			(layers "F.Cu" "F.Mask" "F.Paste")
			(net "EJTAG_TRSTB_R")
			(options
				(clearance outline)
				(anchor circle)
			)
			(primitives
				(gr_poly
					(pts
						(arc
							(start -0.1778 -0.2794)
							(mid -0.249642 -0.249642)
							(end -0.2794 -0.1778)
						)
						(arc
							(start -0.2794 0.1778)
							(mid -0.249642 0.249642)
							(end -0.1778 0.2794)
						)
						(arc
							(start 0.1778 0.2794)
							(mid 0.249642 0.249642)
							(end 0.2794 0.1778)
						)
						(arc
							(start 0.2794 -0.1778)
							(mid 0.249642 -0.249642)
							(end 0.1778 -0.2794)
						)
					)
					(width 0)
					(fill yes)
				)
			)
		)
		(pad "2" smd custom
			(at 0 0.4445 180)
			(size 0.1397 0.1397)
			(layers "F.Cu" "F.Mask" "F.Paste")
			(net "EJTAG_TRSTB")
			(options
				(clearance outline)
				(anchor circle)
			)
			(primitives
				(gr_poly
					(pts
						(arc
							(start -0.1778 -0.2794)
							(mid -0.249642 -0.249642)
							(end -0.2794 -0.1778)
						)
						(arc
							(start -0.2794 0.1778)
							(mid -0.249642 0.249642)
							(end -0.1778 0.2794)
						)
						(arc
							(start 0.1778 0.2794)
							(mid 0.249642 0.249642)
							(end 0.2794 0.1778)
						)
						(arc
							(start 0.2794 -0.1778)
							(mid 0.249642 -0.249642)
							(end 0.1778 -0.2794)
						)
					)
					(width 0)
					(fill yes)
				)
			)
		)
	)
	(footprint ""
		(layer "F.Cu")
		(at 25.019 -147.574 -90)
		(property "Reference" "OSC1"
			(at 0 0 270)
			(layer "F.SilkS")
			(hide yes)
			(effects
				(font
					(size 1.27 1.27)
				)
			)
		)
		(property "Value" "OSC-48MHZ-28-GP"
			(at 0.0127 -2.7686 270)
			(unlocked yes)
			(layer "F.Fab")
			(hide yes)
			(effects
				(font
					(size 1.016 1.016)
					(thickness 0.1524)
				)
			)
		)
		(property "Device Type" "OSC-3225-4P-3H48"
			(at 0.0127 -4.2926 270)
			(unlocked yes)
			(layer "F.Fab")
			(hide yes)
			(effects
				(font
					(size 1.016 1.016)
					(thickness 0.1524)
				)
			)
		)
		(duplicate_pad_numbers_are_jumpers no)
		(fp_line
			(start -2.2352 1.6256)
			(end -2.2352 0.635)
			(stroke
				(width 0.3302)
				(type default)
			)
			(layer "F.SilkS")
		)
		(fp_line
			(start -1.3208 1.6256)
			(end -2.2352 1.6256)
			(stroke
				(width 0.3302)
				(type default)
			)
			(layer "F.SilkS")
		)
		(fp_line
			(start -2.1209 1.5367)
			(end -2.1209 -1.5367)
			(stroke
				(width 0.1524)
				(type default)
			)
			(layer "F.SilkS")
		)
		(fp_line
			(start 2.1209 1.5367)
			(end -2.1209 1.5367)
			(stroke
				(width 0.1524)
				(type default)
			)
			(layer "F.SilkS")
		)
		(fp_line
			(start -2.1209 -1.5367)
			(end 2.1209 -1.5367)
			(stroke
				(width 0.1524)
				(type default)
			)
			(layer "F.SilkS")
		)
		(fp_line
			(start 2.1209 -1.5367)
			(end 2.1209 1.5367)
			(stroke
				(width 0.1524)
				(type default)
			)
			(layer "F.SilkS")
		)
		(fp_poly
			(pts
				(xy -2.8321 1.459992) (xy -2.8321 0.189992) (xy -2.1971 0.824992)
			)
			(stroke
				(width 0)
				(type default)
			)
			(fill yes)
			(layer "F.SilkS")
		)
		(fp_rect
			(start -1.6002 1.2446)
			(end 1.6002 -1.2446)
			(stroke
				(width 0)
				(type default)
			)
			(fill no)
			(layer "F.CrtYd")
		)
		(fp_poly
			(pts
				(xy -2.3749 1.7907) (xy -2.3749 -1.7907) (xy 2.3749 -1.7907) (xy 2.3749 1.7907) (xy 1.6002 1.7907)
				(xy 1.6002 -1.2446) (xy -1.6002 -1.2446) (xy -1.6002 1.2446) (xy 1.59512 1.2446) (xy 1.59512 1.7907)
			)
			(stroke
				(width 0)
				(type default)
			)
			(fill no)
			(layer "F.CrtYd")
		)
		(fp_rect
			(start -2.3749 1.7907)
			(end 2.3749 -1.7907)
			(stroke
				(width 0)
				(type default)
			)
			(fill no)
			(layer "F.Fab")
		)
		(pad "1" smd rect
			(at -1.171448 0.824992 270)
			(size 1.397 0.9144)
			(layers "F.Cu" "F.Mask" "F.Paste")
			(net "OSC2_CONT")
		)
		(pad "2" smd rect
			(at 1.171448 0.824992 270)
			(size 1.397 0.9144)
			(layers "F.Cu" "F.Mask" "F.Paste")
			(net "GND")
		)
		(pad "3" smd rect
			(at 1.171448 -0.824992 270)
			(size 1.397 0.9144)
			(layers "F.Cu" "F.Mask" "F.Paste")
			(net "OSC2_OUT")
		)
		(pad "4" smd rect
			(at -1.171448 -0.824992 270)
			(size 1.397 0.9144)
			(layers "F.Cu" "F.Mask" "F.Paste")
			(net "P3V3_STBY")
		)
		(zone
			(layer "F.Cu")
			(hatch none 0.5)
			(connect_pads
				(clearance 0)
			)
			(min_thickness 0.25)
			(keepout
				(tracks not_allowed)
				(vias allowed)
				(pads allowed)
				(copperpour not_allowed)
				(footprints allowed)
			)
			(placement
				(enabled no)
				(sheetname "")
			)
			(fill
				(thermal_gap 0.5)
				(thermal_bridge_width 0.5)
				(island_removal_mode 0)
			)
			(polygon
				(pts
					(xy 24.976328 -147.721828) (xy 24.976328 -147.426172) (xy 25.061672 -147.426172) (xy 25.061672 -147.721828)
				)
			)
		)
		(zone
			(layer "F.Cu")
			(hatch none 0.5)
			(connect_pads
				(clearance 0)
			)
			(min_thickness 0.25)
			(keepout
				(tracks allowed)
				(vias not_allowed)
				(pads allowed)
				(copperpour not_allowed)
				(footprints allowed)
			)
			(placement
				(enabled no)
				(sheetname "")
			)
			(fill
				(thermal_gap 0.5)
				(thermal_bridge_width 0.5)
				(island_removal_mode 0)
			)
			(polygon
				(pts
					(xy 23.736808 -148.046948) (xy 24.651208 -148.046948) (xy 24.651208 -149.443948) (xy 25.386792 -149.443948)
					(xy 25.386792 -148.046948) (xy 26.301192 -148.046948) (xy 26.301192 -147.101052) (xy 25.386792 -147.101052)
					(xy 25.386792 -145.704052) (xy 24.651208 -145.704052) (xy 24.651208 -147.101052) (xy 23.736808 -147.101052)
				)
			)
		)
	)
	(footprint ""
		(layer "F.Cu")
		(at 149.733 -89.535 180)
		(property "Reference" "PC69"
			(at 0 0 180)
			(layer "F.SilkS")
			(hide yes)
			(effects
				(font
					(size 1.27 1.27)
				)
			)
		)
		(property "Value" "SC4D7U16V5KX-1-GP"
			(at -0.0762 -6.1214 180)
			(unlocked yes)
			(layer "F.Fab")
			(hide yes)
			(effects
				(font
					(size 1.016 1.016)
					(thickness 0.1524)
				)
			)
		)
		(property "Device Type" "C805H56"
			(at -0.0762 -8.1534 180)
			(unlocked yes)
			(layer "F.Fab")
			(hide yes)
			(effects
				(font
					(size 1.016 1.016)
					(thickness 0.1524)
				)
			)
		)
		(duplicate_pad_numbers_are_jumpers no)
		(fp_line
			(start 0.635 0)
			(end -0.635 0)
			(stroke
				(width 0.508)
				(type default)
			)
			(layer "F.SilkS")
		)
		(fp_rect
			(start -0.9652 1.778)
			(end 0.9652 -1.778)
			(stroke
				(width 0)
				(type default)
			)
			(fill no)
			(layer "F.CrtYd")
		)
		(fp_poly
			(pts
				(xy -0.9652 -1.778) (xy 0.9652 -1.778) (xy 0.9652 1.778) (xy -0.9652 1.778)
			)
			(stroke
				(width 0)
				(type default)
			)
			(fill no)
			(layer "F.Fab")
		)
		(pad "1" smd rect
			(at 0 -0.9652 180)
			(size 1.397 1.143)
			(layers "F.Cu" "F.Mask" "F.Paste")
			(net "P1V8_PWR")
		)
		(pad "2" smd rect
			(at 0 0.9652 180)
			(size 1.397 1.143)
			(layers "F.Cu" "F.Mask" "F.Paste")
			(net "GND")
		)
	)
	(footprint ""
		(layer "F.Cu")
		(at 15.0114 -120.4468 90)
		(property "Reference" "R238"
			(at 0 0 90)
			(layer "F.SilkS")
			(hide yes)
			(effects
				(font
					(size 1.27 1.27)
				)
			)
		)
		(property "Value" "0R2J-2-GP"
			(at 0.064008 -3.993896 90)
			(unlocked yes)
			(layer "F.Fab")
			(hide yes)
			(effects
				(font
					(size 1.016 1.016)
					(thickness 0.1524)
				)
			)
		)
		(property "Device Type" "R402H16"
			(at 0.064008 -5.517896 90)
			(unlocked yes)
			(layer "F.Fab")
			(hide yes)
			(effects
				(font
					(size 1.016 1.016)
					(thickness 0.1524)
				)
			)
		)
		(duplicate_pad_numbers_are_jumpers no)
		(fp_line
			(start 0.508 -0.9398)
			(end -0.508 -0.9398)
			(stroke
				(width 0.1524)
				(type default)
			)
			(layer "F.SilkS")
		)
		(fp_line
			(start -0.508 -0.9398)
			(end -0.508 0.9398)
			(stroke
				(width 0.1524)
				(type default)
			)
			(layer "F.SilkS")
		)
		(fp_rect
			(start -0.508 0.9398)
			(end 0.508 -0.9398)
			(stroke
				(width 0)
				(type default)
			)
			(fill no)
			(layer "F.CrtYd")
		)
		(fp_rect
			(start -0.508 0.9398)
			(end 0.508 -0.9398)
			(stroke
				(width 0)
				(type default)
			)
			(fill no)
			(layer "F.Fab")
		)
		(pad "1" smd custom
			(at 0 -0.4445 90)
			(size 0.1397 0.1397)
			(layers "F.Cu" "F.Mask" "F.Paste")
			(net "BMC_I2C1_MINI1_SCL_S")
			(options
				(clearance outline)
				(anchor circle)
			)
			(primitives
				(gr_poly
					(pts
						(arc
							(start -0.1778 -0.2794)
							(mid -0.249642 -0.249642)
							(end -0.2794 -0.1778)
						)
						(arc
							(start -0.2794 0.1778)
							(mid -0.249642 0.249642)
							(end -0.1778 0.2794)
						)
						(arc
							(start 0.1778 0.2794)
							(mid 0.249642 0.249642)
							(end 0.2794 0.1778)
						)
						(arc
							(start 0.2794 -0.1778)
							(mid 0.249642 -0.249642)
							(end 0.1778 -0.2794)
						)
					)
					(width 0)
					(fill yes)
				)
			)
		)
		(pad "2" smd custom
			(at 0 0.4445 90)
			(size 0.1397 0.1397)
			(layers "F.Cu" "F.Mask" "F.Paste")
			(net "BMC0_SMB1_CLK")
			(options
				(clearance outline)
				(anchor circle)
			)
			(primitives
				(gr_poly
					(pts
						(arc
							(start -0.1778 -0.2794)
							(mid -0.249642 -0.249642)
							(end -0.2794 -0.1778)
						)
						(arc
							(start -0.2794 0.1778)
							(mid -0.249642 0.249642)
							(end -0.1778 0.2794)
						)
						(arc
							(start 0.1778 0.2794)
							(mid 0.249642 0.249642)
							(end 0.2794 0.1778)
						)
						(arc
							(start 0.2794 -0.1778)
							(mid 0.249642 -0.249642)
							(end 0.1778 -0.2794)
						)
					)
					(width 0)
					(fill yes)
				)
			)
		)
	)
	(footprint ""
		(layer "F.Cu")
		(at 251.680726 -6.920992 -90)
		(property "Reference" "R270"
			(at 0 0 270)
			(layer "F.SilkS")
			(hide yes)
			(effects
				(font
					(size 1.27 1.27)
				)
			)
		)
		(property "Value" "0R2J-2-GP"
			(at 0.064008 -3.993896 270)
			(unlocked yes)
			(layer "F.Fab")
			(hide yes)
			(effects
				(font
					(size 1.016 1.016)
					(thickness 0.1524)
				)
			)
		)
		(property "Device Type" "R402H16"
			(at 0.064008 -5.517896 270)
			(unlocked yes)
			(layer "F.Fab")
			(hide yes)
			(effects
				(font
					(size 1.016 1.016)
					(thickness 0.1524)
				)
			)
		)
		(duplicate_pad_numbers_are_jumpers no)
		(fp_line
			(start -0.508 -0.9398)
			(end -0.508 0.9398)
			(stroke
				(width 0.1524)
				(type default)
			)
			(layer "F.SilkS")
		)
		(fp_line
			(start 0.508 -0.9398)
			(end -0.508 -0.9398)
			(stroke
				(width 0.1524)
				(type default)
			)
			(layer "F.SilkS")
		)
		(fp_rect
			(start -0.508 0.9398)
			(end 0.508 -0.9398)
			(stroke
				(width 0)
				(type default)
			)
			(fill no)
			(layer "F.CrtYd")
		)
		(fp_rect
			(start -0.508 0.9398)
			(end 0.508 -0.9398)
			(stroke
				(width 0)
				(type default)
			)
			(fill no)
			(layer "F.Fab")
		)
		(pad "1" smd custom
			(at 0 -0.4445 270)
			(size 0.1397 0.1397)
			(layers "F.Cu" "F.Mask" "F.Paste")
			(net "I2C_MAX6654_CLK")
			(options
				(clearance outline)
				(anchor circle)
			)
			(primitives
				(gr_poly
					(pts
						(arc
							(start -0.1778 -0.2794)
							(mid -0.249642 -0.249642)
							(end -0.2794 -0.1778)
						)
						(arc
							(start -0.2794 0.1778)
							(mid -0.249642 0.249642)
							(end -0.1778 0.2794)
						)
						(arc
							(start 0.1778 0.2794)
							(mid 0.249642 0.249642)
							(end 0.2794 0.1778)
						)
						(arc
							(start 0.2794 -0.1778)
							(mid 0.249642 -0.249642)
							(end 0.1778 -0.2794)
						)
					)
					(width 0)
					(fill yes)
				)
			)
		)
		(pad "2" smd custom
			(at 0 0.4445 270)
			(size 0.1397 0.1397)
			(layers "F.Cu" "F.Mask" "F.Paste")
			(net "BMC_I2C5_D_PEB_SCL")
			(options
				(clearance outline)
				(anchor circle)
			)
			(primitives
				(gr_poly
					(pts
						(arc
							(start -0.1778 -0.2794)
							(mid -0.249642 -0.249642)
							(end -0.2794 -0.1778)
						)
						(arc
							(start -0.2794 0.1778)
							(mid -0.249642 0.249642)
							(end -0.1778 0.2794)
						)
						(arc
							(start 0.1778 0.2794)
							(mid 0.249642 0.249642)
							(end 0.2794 0.1778)
						)
						(arc
							(start 0.2794 -0.1778)
							(mid 0.249642 -0.249642)
							(end 0.1778 -0.2794)
						)
					)
					(width 0)
					(fill yes)
				)
			)
		)
	)
	(footprint ""
		(layer "F.Cu")
		(at 298.958 -68.834 180)
		(property "Reference" "C455"
			(at 0 0 180)
			(layer "F.SilkS")
			(hide yes)
			(effects
				(font
					(size 1.27 1.27)
				)
			)
		)
		(property "Value" "SC100U4V5MX-1-GP"
			(at -0.0762 -6.1214 180)
			(unlocked yes)
			(layer "F.Fab")
			(hide yes)
			(effects
				(font
					(size 1.016 1.016)
					(thickness 0.1524)
				)
			)
		)
		(property "Device Type" "C805H58"
			(at -0.0762 -8.1534 180)
			(unlocked yes)
			(layer "F.Fab")
			(hide yes)
			(effects
				(font
					(size 1.016 1.016)
					(thickness 0.1524)
				)
			)
		)
		(duplicate_pad_numbers_are_jumpers no)
		(fp_line
			(start 0.635 0)
			(end -0.635 0)
			(stroke
				(width 0.508)
				(type default)
			)
			(layer "F.SilkS")
		)
		(fp_rect
			(start -0.9652 1.778)
			(end 0.9652 -1.778)
			(stroke
				(width 0)
				(type default)
			)
			(fill no)
			(layer "F.CrtYd")
		)
		(fp_poly
			(pts
				(xy -0.9652 -1.778) (xy 0.9652 -1.778) (xy 0.9652 1.778) (xy -0.9652 1.778)
			)
			(stroke
				(width 0)
				(type default)
			)
			(fill no)
			(layer "F.Fab")
		)
		(pad "1" smd rect
			(at 0 -0.9652 180)
			(size 1.397 1.143)
			(layers "F.Cu" "F.Mask" "F.Paste")
			(net "DUT_VDD")
		)
		(pad "2" smd rect
			(at 0 0.9652 180)
			(size 1.397 1.143)
			(layers "F.Cu" "F.Mask" "F.Paste")
			(net "GND")
		)
	)
)
